FILE_TYPE = CONNECTIVITY;
{Allegro Design Entry HDL 17.4-2019 S026 (4007227) 1/17/2022}
"PAGE_NUMBER" = 5;
0"NC";
END.
